(kicad_pcb
	(version 20260206)
	(generator "pcbnew")
	(generator_version "10.0")
	(general
		(thickness 1.6)
		(legacy_teardrops no)
	)
	(paper "A4")
	(title_block
		(title "01162023_DA0F0TEBIF0_F0T_Expander_BD_F_brd_V02_OCP.brd")
		(comment 1 "Grand Teton / footprints 3419-3427 of 9728")
	)
	(layers
		(0 "F.Cu" signal "TOP")
		(4 "In1.Cu" signal "GND")
		(6 "In2.Cu" signal "VCC")
		(8 "In3.Cu" signal "VCC1")
		(10 "In4.Cu" signal "GND1")
		(12 "In5.Cu" signal "IN1")
		(14 "In6.Cu" signal "GND2")
		(16 "In7.Cu" signal "IN2")
		(18 "In8.Cu" signal "GND3")
		(20 "In9.Cu" signal "IN3")
		(22 "In10.Cu" signal "GND4")
		(24 "In11.Cu" signal "IN4")
		(26 "In12.Cu" signal "GND5")
		(28 "In13.Cu" signal "IN5")
		(30 "In14.Cu" signal "GND6")
		(32 "In15.Cu" signal "IN6")
		(34 "In16.Cu" signal "GND7")
		(2 "B.Cu" signal "BOTTOM")
		(9 "F.Adhes" user "F.Adhesive")
		(11 "B.Adhes" user "B.Adhesive")
		(13 "F.Paste" user "Package Geometry/Pastemask Top")
		(15 "B.Paste" user "Package Geometry/Pastemask Bottom")
		(5 "F.SilkS" user "Ref Des/Silkscreen Top")
		(7 "B.SilkS" user "Ref Des/Silkscreen Bottom")
		(1 "F.Mask" user "Board Geometry/Soldermask Top")
		(3 "B.Mask" user "Board Geometry/Soldermask Bottom")
		(17 "Dwgs.User" user "User.Drawings")
		(19 "Cmts.User" user "User.Comments")
		(21 "Eco1.User" user "User.Eco1")
		(23 "Eco2.User" user "User.Eco2")
		(25 "Edge.Cuts" user "Board Geometry/Outline")
		(27 "Margin" user)
		(31 "F.CrtYd" user "Package Geometry/Place Bound Top")
		(29 "B.CrtYd" user "Package Geometry/Place Bound Bottom")
		(35 "F.Fab" user "Ref Des/Assembly Top")
		(33 "B.Fab" user "Ref Des/Assembly Bottom")
	)
	(footprint ""
		(layer "F.Cu")
		(at 219.202 -206.756)
		(property "Reference" "R1509"
			(at 0 0 0)
			(layer "F.SilkS")
			(hide yes)
			(effects
				(font
					(size 1.27 1.27)
				)
			)
		)
		(property "Value" ""
			(at 0 0 0)
			(layer "F.Fab")
			(effects
				(font
					(size 1.27 1.27)
				)
			)
		)
		(duplicate_pad_numbers_are_jumpers no)
		(fp_line
			(start -0.7874 -0.4064)
			(end 0.7874 -0.4064)
			(stroke
				(width 0.1524)
				(type default)
			)
			(layer "F.SilkS")
		)
		(fp_line
			(start -0.7874 0.4064)
			(end -0.7874 -0.4064)
			(stroke
				(width 0.1524)
				(type default)
			)
			(layer "F.SilkS")
		)
		(fp_line
			(start 0.7874 -0.4064)
			(end 0.7874 0.4064)
			(stroke
				(width 0.1524)
				(type default)
			)
			(layer "F.SilkS")
		)
		(fp_line
			(start 0.7874 0.4064)
			(end -0.7874 0.4064)
			(stroke
				(width 0.1524)
				(type default)
			)
			(layer "F.SilkS")
		)
		(fp_line
			(start -0.67945 -0.305054)
			(end -0.12065 -0.305054)
			(stroke
				(width 0.1)
				(type default)
			)
			(layer "F.Fab")
		)
		(fp_line
			(start -0.67945 0.3048)
			(end -0.67945 -0.305054)
			(stroke
				(width 0.1)
				(type default)
			)
			(layer "F.Fab")
		)
		(fp_line
			(start -0.12065 -0.305054)
			(end -0.12065 -0.2794)
			(stroke
				(width 0.1)
				(type default)
			)
			(layer "F.Fab")
		)
		(fp_line
			(start -0.12065 -0.2794)
			(end 0.12065 -0.2794)
			(stroke
				(width 0.1)
				(type default)
			)
			(layer "F.Fab")
		)
		(fp_line
			(start -0.12065 0.2794)
			(end -0.12065 0.3048)
			(stroke
				(width 0.1)
				(type default)
			)
			(layer "F.Fab")
		)
		(fp_line
			(start -0.12065 0.3048)
			(end -0.67945 0.3048)
			(stroke
				(width 0.1)
				(type default)
			)
			(layer "F.Fab")
		)
		(fp_line
			(start 0.120396 0.2794)
			(end -0.12065 0.2794)
			(stroke
				(width 0.1)
				(type default)
			)
			(layer "F.Fab")
		)
		(fp_line
			(start 0.120396 0.3048)
			(end 0.120396 0.2794)
			(stroke
				(width 0.1)
				(type default)
			)
			(layer "F.Fab")
		)
		(fp_line
			(start 0.12065 -0.3048)
			(end 0.67945 -0.3048)
			(stroke
				(width 0.1)
				(type default)
			)
			(layer "F.Fab")
		)
		(fp_line
			(start 0.12065 -0.2794)
			(end 0.12065 -0.3048)
			(stroke
				(width 0.1)
				(type default)
			)
			(layer "F.Fab")
		)
		(fp_line
			(start 0.67945 -0.3048)
			(end 0.67945 0.3048)
			(stroke
				(width 0.1)
				(type default)
			)
			(layer "F.Fab")
		)
		(fp_line
			(start 0.67945 0.3048)
			(end 0.120396 0.3048)
			(stroke
				(width 0.1)
				(type default)
			)
			(layer "F.Fab")
		)
		(pad "1" smd circle
			(at -0.40005 0)
			(size 0 0)
			(layers "F.Cu" "F.Mask" "F.Paste")
			(net "SMB_NIC4_LS_R_SCL")
		)
		(pad "2" smd circle
			(at 0.40005 0)
			(size 0 0)
			(layers "F.Cu" "F.Mask" "F.Paste")
			(net "P3V3_NIC4")
		)
	)
	(footprint ""
		(layer "F.Cu")
		(at 430.961546 -136.20115 180)
		(property "Reference" "C650"
			(at 0 0 180)
			(layer "F.SilkS")
			(hide yes)
			(effects
				(font
					(size 1.27 1.27)
				)
			)
		)
		(property "Value" ""
			(at 0 0 180)
			(layer "F.Fab")
			(effects
				(font
					(size 1.27 1.27)
				)
			)
		)
		(duplicate_pad_numbers_are_jumpers no)
		(fp_line
			(start 0.299974 0.150114)
			(end -0.299974 0.150114)
			(stroke
				(width 0.1)
				(type default)
			)
			(layer "F.Fab")
		)
		(fp_line
			(start 0.299974 -0.150114)
			(end 0.299974 0.150114)
			(stroke
				(width 0.1)
				(type default)
			)
			(layer "F.Fab")
		)
		(fp_line
			(start -0.299974 0.150114)
			(end -0.299974 -0.150114)
			(stroke
				(width 0.1)
				(type default)
			)
			(layer "F.Fab")
		)
		(fp_line
			(start -0.299974 -0.150114)
			(end 0.299974 -0.150114)
			(stroke
				(width 0.1)
				(type default)
			)
			(layer "F.Fab")
		)
		(pad "1" smd rect
			(at -0.2667 0 180)
			(size 0.3048 0.381)
			(layers "F.Cu" "F.Mask" "F.Paste")
			(net "P5E_PEX3_STN0_TX_DP<7>")
		)
		(pad "2" smd rect
			(at 0.2667 0 180)
			(size 0.3048 0.381)
			(layers "F.Cu" "F.Mask" "F.Paste")
			(net "P5E_PEX3_STN0_TX_C_DP<7>")
		)
	)
	(footprint ""
		(layer "F.Cu")
		(at 143.030194 -300.406308 -90)
		(property "Reference" "C3191"
			(at 0 0 270)
			(layer "F.SilkS")
			(hide yes)
			(effects
				(font
					(size 1.27 1.27)
				)
			)
		)
		(property "Value" ""
			(at 0 0 270)
			(layer "F.Fab")
			(effects
				(font
					(size 1.27 1.27)
				)
			)
		)
		(duplicate_pad_numbers_are_jumpers no)
		(fp_line
			(start -1.2954 0.5842)
			(end -1.2954 -0.5842)
			(stroke
				(width 0.1524)
				(type default)
			)
			(layer "F.SilkS")
		)
		(fp_line
			(start 1.2954 0.5842)
			(end -1.2954 0.5842)
			(stroke
				(width 0.1524)
				(type default)
			)
			(layer "F.SilkS")
		)
		(fp_line
			(start -1.2954 -0.5842)
			(end 1.2954 -0.5842)
			(stroke
				(width 0.1524)
				(type default)
			)
			(layer "F.SilkS")
		)
		(fp_line
			(start 1.2954 -0.5842)
			(end 1.2954 0.5842)
			(stroke
				(width 0.1524)
				(type default)
			)
			(layer "F.SilkS")
		)
		(fp_line
			(start -0.8636 0.4572)
			(end -0.8636 0.4064)
			(stroke
				(width 0.1)
				(type default)
			)
			(layer "F.Fab")
		)
		(fp_line
			(start 0.8636 0.4572)
			(end -0.8636 0.4572)
			(stroke
				(width 0.1)
				(type default)
			)
			(layer "F.Fab")
		)
		(fp_line
			(start -1.1938 0.4064)
			(end -1.1938 -0.4064)
			(stroke
				(width 0.1)
				(type default)
			)
			(layer "F.Fab")
		)
		(fp_line
			(start -0.8636 0.4064)
			(end -1.1938 0.4064)
			(stroke
				(width 0.1)
				(type default)
			)
			(layer "F.Fab")
		)
		(fp_line
			(start 0.8636 0.4064)
			(end 0.8636 0.4572)
			(stroke
				(width 0.1)
				(type default)
			)
			(layer "F.Fab")
		)
		(fp_line
			(start 1.1938 0.4064)
			(end 0.8636 0.4064)
			(stroke
				(width 0.1)
				(type default)
			)
			(layer "F.Fab")
		)
		(fp_line
			(start -1.1938 -0.4064)
			(end -0.8636 -0.4064)
			(stroke
				(width 0.1)
				(type default)
			)
			(layer "F.Fab")
		)
		(fp_line
			(start -0.8636 -0.4064)
			(end -0.8636 -0.4572)
			(stroke
				(width 0.1)
				(type default)
			)
			(layer "F.Fab")
		)
		(fp_line
			(start 0.8636 -0.4064)
			(end 1.1938 -0.4064)
			(stroke
				(width 0.1)
				(type default)
			)
			(layer "F.Fab")
		)
		(fp_line
			(start 1.1938 -0.4064)
			(end 1.1938 0.4064)
			(stroke
				(width 0.1)
				(type default)
			)
			(layer "F.Fab")
		)
		(fp_line
			(start -0.8636 -0.4572)
			(end 0.8636 -0.4572)
			(stroke
				(width 0.1)
				(type default)
			)
			(layer "F.Fab")
		)
		(fp_line
			(start 0.8636 -0.4572)
			(end 0.8636 -0.4064)
			(stroke
				(width 0.1)
				(type default)
			)
			(layer "F.Fab")
		)
		(pad "1" smd rect
			(at -0.7366 0 180)
			(size 0.7112 0.8128)
			(layers "F.Cu" "F.Mask" "F.Paste")
			(net "P1V8_PLL0_PEX1")
		)
		(pad "2" smd rect
			(at 0.7366 0 180)
			(size 0.7112 0.8128)
			(layers "F.Cu" "F.Mask" "F.Paste")
			(net "GND")
		)
	)
	(footprint ""
		(layer "F.Cu")
		(at 73.782682 -350.098614 90)
		(property "Reference" "C115"
			(at 0 0 90)
			(layer "F.SilkS")
			(hide yes)
			(effects
				(font
					(size 1.27 1.27)
				)
			)
		)
		(property "Value" ""
			(at 0 0 90)
			(layer "F.Fab")
			(effects
				(font
					(size 1.27 1.27)
				)
			)
		)
		(duplicate_pad_numbers_are_jumpers no)
		(fp_line
			(start 0.299974 -0.150114)
			(end 0.299974 0.150114)
			(stroke
				(width 0.1)
				(type default)
			)
			(layer "F.Fab")
		)
		(fp_line
			(start -0.299974 -0.150114)
			(end 0.299974 -0.150114)
			(stroke
				(width 0.1)
				(type default)
			)
			(layer "F.Fab")
		)
		(fp_line
			(start 0.299974 0.150114)
			(end -0.299974 0.150114)
			(stroke
				(width 0.1)
				(type default)
			)
			(layer "F.Fab")
		)
		(fp_line
			(start -0.299974 0.150114)
			(end -0.299974 -0.150114)
			(stroke
				(width 0.1)
				(type default)
			)
			(layer "F.Fab")
		)
		(pad "1" smd rect
			(at -0.2667 0 90)
			(size 0.3048 0.381)
			(layers "F.Cu" "F.Mask" "F.Paste")
			(net "P5E_PEX0_STN5_TX_DP<86>")
		)
		(pad "2" smd rect
			(at 0.2667 0 90)
			(size 0.3048 0.381)
			(layers "F.Cu" "F.Mask" "F.Paste")
			(net "P5E_PEX0_STN5_TX_C_DP<86>")
		)
	)
	(footprint ""
		(layer "F.Cu")
		(at 244.221762 -178.519328 -90)
		(property "Reference" "C2147"
			(at 0 0 270)
			(layer "F.SilkS")
			(hide yes)
			(effects
				(font
					(size 1.27 1.27)
				)
			)
		)
		(property "Value" ""
			(at 0 0 270)
			(layer "F.Fab")
			(effects
				(font
					(size 1.27 1.27)
				)
			)
		)
		(duplicate_pad_numbers_are_jumpers no)
		(fp_line
			(start -0.7874 0.4064)
			(end -0.7874 -0.4064)
			(stroke
				(width 0.1524)
				(type default)
			)
			(layer "F.SilkS")
		)
		(fp_line
			(start 0.7874 0.4064)
			(end -0.7874 0.4064)
			(stroke
				(width 0.1524)
				(type default)
			)
			(layer "F.SilkS")
		)
		(fp_line
			(start -0.7874 -0.4064)
			(end 0.7874 -0.4064)
			(stroke
				(width 0.1524)
				(type default)
			)
			(layer "F.SilkS")
		)
		(fp_line
			(start 0.7874 -0.4064)
			(end 0.7874 0.4064)
			(stroke
				(width 0.1524)
				(type default)
			)
			(layer "F.SilkS")
		)
		(fp_line
			(start -0.67945 0.3048)
			(end -0.67945 -0.305054)
			(stroke
				(width 0.1)
				(type default)
			)
			(layer "F.Fab")
		)
		(fp_line
			(start -0.12065 0.3048)
			(end -0.67945 0.3048)
			(stroke
				(width 0.1)
				(type default)
			)
			(layer "F.Fab")
		)
		(fp_line
			(start 0.120396 0.3048)
			(end 0.120396 0.2794)
			(stroke
				(width 0.1)
				(type default)
			)
			(layer "F.Fab")
		)
		(fp_line
			(start 0.67945 0.3048)
			(end 0.120396 0.3048)
			(stroke
				(width 0.1)
				(type default)
			)
			(layer "F.Fab")
		)
		(fp_line
			(start -0.12065 0.2794)
			(end -0.12065 0.3048)
			(stroke
				(width 0.1)
				(type default)
			)
			(layer "F.Fab")
		)
		(fp_line
			(start 0.120396 0.2794)
			(end -0.12065 0.2794)
			(stroke
				(width 0.1)
				(type default)
			)
			(layer "F.Fab")
		)
		(fp_line
			(start -0.12065 -0.2794)
			(end 0.12065 -0.2794)
			(stroke
				(width 0.1)
				(type default)
			)
			(layer "F.Fab")
		)
		(fp_line
			(start 0.12065 -0.2794)
			(end 0.12065 -0.3048)
			(stroke
				(width 0.1)
				(type default)
			)
			(layer "F.Fab")
		)
		(fp_line
			(start 0.12065 -0.3048)
			(end 0.67945 -0.3048)
			(stroke
				(width 0.1)
				(type default)
			)
			(layer "F.Fab")
		)
		(fp_line
			(start 0.67945 -0.3048)
			(end 0.67945 0.3048)
			(stroke
				(width 0.1)
				(type default)
			)
			(layer "F.Fab")
		)
		(fp_line
			(start -0.67945 -0.305054)
			(end -0.12065 -0.305054)
			(stroke
				(width 0.1)
				(type default)
			)
			(layer "F.Fab")
		)
		(fp_line
			(start -0.12065 -0.305054)
			(end -0.12065 -0.2794)
			(stroke
				(width 0.1)
				(type default)
			)
			(layer "F.Fab")
		)
		(pad "1" smd circle
			(at -0.40005 0 270)
			(size 0 0)
			(layers "F.Cu" "F.Mask" "F.Paste")
			(net "P3V3_AUX")
		)
		(pad "2" smd circle
			(at 0.40005 0 270)
			(size 0 0)
			(layers "F.Cu" "F.Mask" "F.Paste")
			(net "GND")
		)
	)
	(footprint ""
		(layer "F.Cu")
		(at 252.634496 -34.546286 180)
		(property "Reference" "C487"
			(at 0 0 180)
			(layer "F.SilkS")
			(hide yes)
			(effects
				(font
					(size 1.27 1.27)
				)
			)
		)
		(property "Value" ""
			(at 0 0 180)
			(layer "F.Fab")
			(effects
				(font
					(size 1.27 1.27)
				)
			)
		)
		(duplicate_pad_numbers_are_jumpers no)
		(fp_line
			(start 0.299974 0.150114)
			(end -0.299974 0.150114)
			(stroke
				(width 0.1)
				(type default)
			)
			(layer "F.Fab")
		)
		(fp_line
			(start 0.299974 -0.150114)
			(end 0.299974 0.150114)
			(stroke
				(width 0.1)
				(type default)
			)
			(layer "F.Fab")
		)
		(fp_line
			(start -0.299974 0.150114)
			(end -0.299974 -0.150114)
			(stroke
				(width 0.1)
				(type default)
			)
			(layer "F.Fab")
		)
		(fp_line
			(start -0.299974 -0.150114)
			(end 0.299974 -0.150114)
			(stroke
				(width 0.1)
				(type default)
			)
			(layer "F.Fab")
		)
		(pad "1" smd rect
			(at -0.2667 0 180)
			(size 0.3048 0.381)
			(layers "F.Cu" "F.Mask" "F.Paste")
			(net "P5E_PEX2_STN2_TX_DP<47>")
		)
		(pad "2" smd rect
			(at 0.2667 0 180)
			(size 0.3048 0.381)
			(layers "F.Cu" "F.Mask" "F.Paste")
			(net "P5E_PEX2_STN2_TX_C_DP<47>")
		)
	)
	(footprint ""
		(layer "F.Cu")
		(at 316.500764 -356.244906 90)
		(property "Reference" "C546"
			(at 0 0 90)
			(layer "F.SilkS")
			(hide yes)
			(effects
				(font
					(size 1.27 1.27)
				)
			)
		)
		(property "Value" ""
			(at 0 0 90)
			(layer "F.Fab")
			(effects
				(font
					(size 1.27 1.27)
				)
			)
		)
		(duplicate_pad_numbers_are_jumpers no)
		(fp_line
			(start 0.299974 -0.150114)
			(end 0.299974 0.150114)
			(stroke
				(width 0.1)
				(type default)
			)
			(layer "F.Fab")
		)
		(fp_line
			(start -0.299974 -0.150114)
			(end 0.299974 -0.150114)
			(stroke
				(width 0.1)
				(type default)
			)
			(layer "F.Fab")
		)
		(fp_line
			(start 0.299974 0.150114)
			(end -0.299974 0.150114)
			(stroke
				(width 0.1)
				(type default)
			)
			(layer "F.Fab")
		)
		(fp_line
			(start -0.299974 0.150114)
			(end -0.299974 -0.150114)
			(stroke
				(width 0.1)
				(type default)
			)
			(layer "F.Fab")
		)
		(pad "1" smd rect
			(at -0.2667 0 90)
			(size 0.3048 0.381)
			(layers "F.Cu" "F.Mask" "F.Paste")
			(net "P5E_PEX2_STN5_TX_DN<82>")
		)
		(pad "2" smd rect
			(at 0.2667 0 90)
			(size 0.3048 0.381)
			(layers "F.Cu" "F.Mask" "F.Paste")
			(net "P5E_PEX2_STN5_TX_C_DN<82>")
		)
	)
	(footprint ""
		(layer "F.Cu")
		(at 39.280592 -106.488738)
		(property "Reference" "C55"
			(at 0 0 0)
			(layer "F.SilkS")
			(hide yes)
			(effects
				(font
					(size 1.27 1.27)
				)
			)
		)
		(property "Value" ""
			(at 0 0 0)
			(layer "F.Fab")
			(effects
				(font
					(size 1.27 1.27)
				)
			)
		)
		(duplicate_pad_numbers_are_jumpers no)
		(fp_line
			(start -0.299974 -0.150114)
			(end 0.299974 -0.150114)
			(stroke
				(width 0.1)
				(type default)
			)
			(layer "F.Fab")
		)
		(fp_line
			(start -0.299974 0.150114)
			(end -0.299974 -0.150114)
			(stroke
				(width 0.1)
				(type default)
			)
			(layer "F.Fab")
		)
		(fp_line
			(start 0.299974 -0.150114)
			(end 0.299974 0.150114)
			(stroke
				(width 0.1)
				(type default)
			)
			(layer "F.Fab")
		)
		(fp_line
			(start 0.299974 0.150114)
			(end -0.299974 0.150114)
			(stroke
				(width 0.1)
				(type default)
			)
			(layer "F.Fab")
		)
		(pad "1" smd rect
			(at -0.2667 0)
			(size 0.3048 0.381)
			(layers "F.Cu" "F.Mask" "F.Paste")
			(net "P5E_PEX0_STN1_TX_DP<20>")
		)
		(pad "2" smd rect
			(at 0.2667 0)
			(size 0.3048 0.381)
			(layers "F.Cu" "F.Mask" "F.Paste")
			(net "P5E_PEX0_STN1_TX_C_DP<20>")
		)
	)
	(footprint ""
		(layer "F.Cu")
		(at 19.796252 -47.20082 90)
		(property "Reference" "C202"
			(at 0 0 90)
			(layer "F.SilkS")
			(hide yes)
			(effects
				(font
					(size 1.27 1.27)
				)
			)
		)
		(property "Value" ""
			(at 0 0 90)
			(layer "F.Fab")
			(effects
				(font
					(size 1.27 1.27)
				)
			)
		)
		(duplicate_pad_numbers_are_jumpers no)
		(fp_line
			(start 0.7874 -0.4064)
			(end 0.7874 0.4064)
			(stroke
				(width 0.1524)
				(type default)
			)
			(layer "F.SilkS")
		)
		(fp_line
			(start -0.7874 -0.4064)
			(end 0.7874 -0.4064)
			(stroke
				(width 0.1524)
				(type default)
			)
			(layer "F.SilkS")
		)
		(fp_line
			(start 0.7874 0.4064)
			(end -0.7874 0.4064)
			(stroke
				(width 0.1524)
				(type default)
			)
			(layer "F.SilkS")
		)
		(fp_line
			(start -0.7874 0.4064)
			(end -0.7874 -0.4064)
			(stroke
				(width 0.1524)
				(type default)
			)
			(layer "F.SilkS")
		)
		(fp_line
			(start -0.12065 -0.305054)
			(end -0.12065 -0.2794)
			(stroke
				(width 0.1)
				(type default)
			)
			(layer "F.Fab")
		)
		(fp_line
			(start -0.67945 -0.305054)
			(end -0.12065 -0.305054)
			(stroke
				(width 0.1)
				(type default)
			)
			(layer "F.Fab")
		)
		(fp_line
			(start 0.67945 -0.3048)
			(end 0.67945 0.3048)
			(stroke
				(width 0.1)
				(type default)
			)
			(layer "F.Fab")
		)
		(fp_line
			(start 0.12065 -0.3048)
			(end 0.67945 -0.3048)
			(stroke
				(width 0.1)
				(type default)
			)
			(layer "F.Fab")
		)
		(fp_line
			(start 0.12065 -0.2794)
			(end 0.12065 -0.3048)
			(stroke
				(width 0.1)
				(type default)
			)
			(layer "F.Fab")
		)
		(fp_line
			(start -0.12065 -0.2794)
			(end 0.12065 -0.2794)
			(stroke
				(width 0.1)
				(type default)
			)
			(layer "F.Fab")
		)
		(fp_line
			(start 0.120396 0.2794)
			(end -0.12065 0.2794)
			(stroke
				(width 0.1)
				(type default)
			)
			(layer "F.Fab")
		)
		(fp_line
			(start -0.12065 0.2794)
			(end -0.12065 0.3048)
			(stroke
				(width 0.1)
				(type default)
			)
			(layer "F.Fab")
		)
		(fp_line
			(start 0.67945 0.3048)
			(end 0.120396 0.3048)
			(stroke
				(width 0.1)
				(type default)
			)
			(layer "F.Fab")
		)
		(fp_line
			(start 0.120396 0.3048)
			(end 0.120396 0.2794)
			(stroke
				(width 0.1)
				(type default)
			)
			(layer "F.Fab")
		)
		(fp_line
			(start -0.12065 0.3048)
			(end -0.67945 0.3048)
			(stroke
				(width 0.1)
				(type default)
			)
			(layer "F.Fab")
		)
		(fp_line
			(start -0.67945 0.3048)
			(end -0.67945 -0.305054)
			(stroke
				(width 0.1)
				(type default)
			)
			(layer "F.Fab")
		)
		(pad "1" smd circle
			(at -0.40005 0 90)
			(size 0 0)
			(layers "F.Cu" "F.Mask" "F.Paste")
			(net "P12V_SSD0_R")
		)
		(pad "2" smd circle
			(at 0.40005 0 90)
			(size 0 0)
			(layers "F.Cu" "F.Mask" "F.Paste")
			(net "GND")
		)
	)
)
